# S9S_MB_2U (Grand Teton) — schematic netlist excerpt (pin names and nets, part order shuffled) for the footprints in the layout excerpt that follows; sources: Cadence DE-HDL packaged netlist, KiCad conversion of 03242023_DA0F0TMBIJ0_F0T_Motherboard_J_brd_V01_OCP.brd

PR1304  Q_RES  8.87K 1% EMPTY  pkg 0402LF  page 290 : A = PVCCFA_EHV_FIVRA_CPU1_LSET4 ; B = GND
R2925  Q_RES  49.9 1% CHIP  pkg 0402LF  page 151 : A = FM_GPU_PWR_EN_R1 ; B = FM_GPU_PWR_EN_R_BUF

(kicad_pcb
	(version 20260206)
	(generator "pcbnew")
	(generator_version "10.0")
	(general
		(thickness 1.6)
		(legacy_teardrops no)
	)
	(paper "A4")
	(title_block
		(title "03242023_DA0F0TMBIJ0_F0T_Motherboard_J_brd_V01_OCP.brd")
		(comment 1 "Grand Teton / footprints 2329-2330 of 6105")
	)
	(layers
		(0 "F.Cu" signal "TOP")
		(4 "In1.Cu" signal "GND")
		(6 "In2.Cu" signal "IN1")
		(8 "In3.Cu" signal "GND1")
		(10 "In4.Cu" signal "IN2")
		(12 "In5.Cu" signal "GND2")
		(14 "In6.Cu" signal "IN3")
		(16 "In7.Cu" signal "GND3")
		(18 "In8.Cu" signal "VCC")
		(20 "In9.Cu" signal "VCC1")
		(22 "In10.Cu" signal "GND4")
		(24 "In11.Cu" signal "IN4")
		(26 "In12.Cu" signal "GND5")
		(28 "In13.Cu" signal "IN5")
		(30 "In14.Cu" signal "GND6")
		(32 "In15.Cu" signal "IN6")
		(34 "In16.Cu" signal "GND7")
		(2 "B.Cu" signal "BOTTOM")
		(9 "F.Adhes" user "F.Adhesive")
		(11 "B.Adhes" user "B.Adhesive")
		(13 "F.Paste" user "Package Geometry/Pastemask Top")
		(15 "B.Paste" user "Package Geometry/Pastemask Bottom")
		(5 "F.SilkS" user "Ref Des/Silkscreen Top")
		(7 "B.SilkS" user "Ref Des/Silkscreen Bottom")
		(1 "F.Mask" user "Board Geometry/Soldermask Top")
		(3 "B.Mask" user "Board Geometry/Soldermask Bottom")
		(17 "Dwgs.User" user "User.Drawings")
		(19 "Cmts.User" user "User.Comments")
		(21 "Eco1.User" user "User.Eco1")
		(23 "Eco2.User" user "User.Eco2")
		(25 "Edge.Cuts" user "Board Geometry/Outline")
		(27 "Margin" user)
		(31 "F.CrtYd" user "Package Geometry/Place Bound Top")
		(29 "B.CrtYd" user "Package Geometry/Place Bound Bottom")
		(35 "F.Fab" user "Ref Des/Assembly Top")
		(33 "B.Fab" user "Ref Des/Assembly Bottom")
	)
	(footprint ""
		(layer "F.Cu")
		(at 40.273732 -358.691942)
		(property "Reference" "PR1304"
			(at 0 0 0)
			(layer "F.SilkS")
			(hide yes)
			(effects
				(font
					(size 1.27 1.27)
				)
			)
		)
		(property "Value" ""
			(at 0 0 0)
			(layer "F.Fab")
			(effects
				(font
					(size 1.27 1.27)
				)
			)
		)
		(duplicate_pad_numbers_are_jumpers no)
		(fp_line
			(start -0.7874 -0.4064)
			(end 0.7874 -0.4064)
			(stroke
				(width 0.1524)
				(type default)
			)
			(layer "F.SilkS")
		)
		(fp_line
			(start -0.7874 0.4064)
			(end -0.7874 -0.4064)
			(stroke
				(width 0.1524)
				(type default)
			)
			(layer "F.SilkS")
		)
		(fp_line
			(start 0.7874 -0.4064)
			(end 0.7874 0.4064)
			(stroke
				(width 0.1524)
				(type default)
			)
			(layer "F.SilkS")
		)
		(fp_line
			(start 0.7874 0.4064)
			(end -0.7874 0.4064)
			(stroke
				(width 0.1524)
				(type default)
			)
			(layer "F.SilkS")
		)
		(fp_line
			(start -0.67945 -0.305054)
			(end -0.12065 -0.305054)
			(stroke
				(width 0.1)
				(type default)
			)
			(layer "F.Fab")
		)
		(fp_line
			(start -0.67945 0.3048)
			(end -0.67945 -0.305054)
			(stroke
				(width 0.1)
				(type default)
			)
			(layer "F.Fab")
		)
		(fp_line
			(start -0.12065 -0.305054)
			(end -0.12065 -0.2794)
			(stroke
				(width 0.1)
				(type default)
			)
			(layer "F.Fab")
		)
		(fp_line
			(start -0.12065 -0.2794)
			(end 0.12065 -0.2794)
			(stroke
				(width 0.1)
				(type default)
			)
			(layer "F.Fab")
		)
		(fp_line
			(start -0.12065 0.2794)
			(end -0.12065 0.3048)
			(stroke
				(width 0.1)
				(type default)
			)
			(layer "F.Fab")
		)
		(fp_line
			(start -0.12065 0.3048)
			(end -0.67945 0.3048)
			(stroke
				(width 0.1)
				(type default)
			)
			(layer "F.Fab")
		)
		(fp_line
			(start 0.120396 0.2794)
			(end -0.12065 0.2794)
			(stroke
				(width 0.1)
				(type default)
			)
			(layer "F.Fab")
		)
		(fp_line
			(start 0.120396 0.3048)
			(end 0.120396 0.2794)
			(stroke
				(width 0.1)
				(type default)
			)
			(layer "F.Fab")
		)
		(fp_line
			(start 0.12065 -0.3048)
			(end 0.67945 -0.3048)
			(stroke
				(width 0.1)
				(type default)
			)
			(layer "F.Fab")
		)
		(fp_line
			(start 0.12065 -0.2794)
			(end 0.12065 -0.3048)
			(stroke
				(width 0.1)
				(type default)
			)
			(layer "F.Fab")
		)
		(fp_line
			(start 0.67945 -0.3048)
			(end 0.67945 0.3048)
			(stroke
				(width 0.1)
				(type default)
			)
			(layer "F.Fab")
		)
		(fp_line
			(start 0.67945 0.3048)
			(end 0.120396 0.3048)
			(stroke
				(width 0.1)
				(type default)
			)
			(layer "F.Fab")
		)
		(pad "1" smd circle
			(at -0.40005 0)
			(size 0 0)
			(layers "F.Cu" "F.Mask" "F.Paste")
			(net "PVCCFA_EHV_FIVRA_CPU1_LSET4")
		)
		(pad "2" smd circle
			(at 0.40005 0)
			(size 0 0)
			(layers "F.Cu" "F.Mask" "F.Paste")
			(net "GND")
		)
	)
	(footprint ""
		(layer "F.Cu")
		(at 120.37822 -421.447468)
		(property "Reference" "R2925"
			(at 0 0 0)
			(layer "F.SilkS")
			(hide yes)
			(effects
				(font
					(size 1.27 1.27)
				)
			)
		)
		(property "Value" ""
			(at 0 0 0)
			(layer "F.Fab")
			(effects
				(font
					(size 1.27 1.27)
				)
			)
		)
		(duplicate_pad_numbers_are_jumpers no)
		(fp_line
			(start -0.7874 -0.4064)
			(end 0.7874 -0.4064)
			(stroke
				(width 0.1524)
				(type default)
			)
			(layer "F.SilkS")
		)
		(fp_line
			(start -0.7874 0.4064)
			(end -0.7874 -0.4064)
			(stroke
				(width 0.1524)
				(type default)
			)
			(layer "F.SilkS")
		)
		(fp_line
			(start 0.7874 -0.4064)
			(end 0.7874 0.4064)
			(stroke
				(width 0.1524)
				(type default)
			)
			(layer "F.SilkS")
		)
		(fp_line
			(start 0.7874 0.4064)
			(end -0.7874 0.4064)
			(stroke
				(width 0.1524)
				(type default)
			)
			(layer "F.SilkS")
		)
		(fp_line
			(start -0.67945 -0.305054)
			(end -0.12065 -0.305054)
			(stroke
				(width 0.1)
				(type default)
			)
			(layer "F.Fab")
		)
		(fp_line
			(start -0.67945 0.3048)
			(end -0.67945 -0.305054)
			(stroke
				(width 0.1)
				(type default)
			)
			(layer "F.Fab")
		)
		(fp_line
			(start -0.12065 -0.305054)
			(end -0.12065 -0.2794)
			(stroke
				(width 0.1)
				(type default)
			)
			(layer "F.Fab")
		)
		(fp_line
			(start -0.12065 -0.2794)
			(end 0.12065 -0.2794)
			(stroke
				(width 0.1)
				(type default)
			)
			(layer "F.Fab")
		)
		(fp_line
			(start -0.12065 0.2794)
			(end -0.12065 0.3048)
			(stroke
				(width 0.1)
				(type default)
			)
			(layer "F.Fab")
		)
		(fp_line
			(start -0.12065 0.3048)
			(end -0.67945 0.3048)
			(stroke
				(width 0.1)
				(type default)
			)
			(layer "F.Fab")
		)
		(fp_line
			(start 0.120396 0.2794)
			(end -0.12065 0.2794)
			(stroke
				(width 0.1)
				(type default)
			)
			(layer "F.Fab")
		)
		(fp_line
			(start 0.120396 0.3048)
			(end 0.120396 0.2794)
			(stroke
				(width 0.1)
				(type default)
			)
			(layer "F.Fab")
		)
		(fp_line
			(start 0.12065 -0.3048)
			(end 0.67945 -0.3048)
			(stroke
				(width 0.1)
				(type default)
			)
			(layer "F.Fab")
		)
		(fp_line
			(start 0.12065 -0.2794)
			(end 0.12065 -0.3048)
			(stroke
				(width 0.1)
				(type default)
			)
			(layer "F.Fab")
		)
		(fp_line
			(start 0.67945 -0.3048)
			(end 0.67945 0.3048)
			(stroke
				(width 0.1)
				(type default)
			)
			(layer "F.Fab")
		)
		(fp_line
			(start 0.67945 0.3048)
			(end 0.120396 0.3048)
			(stroke
				(width 0.1)
				(type default)
			)
			(layer "F.Fab")
		)
		(pad "1" smd circle
			(at -0.40005 0)
			(size 0 0)
			(layers "F.Cu" "F.Mask" "F.Paste")
			(net "FM_GPU_PWR_EN_R1")
		)
		(pad "2" smd circle
			(at 0.40005 0)
			(size 0 0)
			(layers "F.Cu" "F.Mask" "F.Paste")
			(net "FM_GPU_PWR_EN_R_BUF")
		)
	)
)
